(kicad_pcb
	(version 20260206)
	(generator "pcbnew")
	(generator_version "10.0")
	(general
		(thickness 1.6)
		(legacy_teardrops no)
	)
	(paper "A4")
	(title_block
		(title "04192023_DAF0TMB3IC0_F0TG_MB_C_brd_V02_OCP.brd")
		(comment 1 "Grand Teton / footprint 3955 of 8354 (U25), pads 5558-5667 of 6102")
	)
	(layers
		(0 "F.Cu" signal "TOP")
		(4 "In1.Cu" signal "GND")
		(6 "In2.Cu" signal "IN1")
		(8 "In3.Cu" signal "GND1")
		(10 "In4.Cu" signal "IN2")
		(12 "In5.Cu" signal "GND2")
		(14 "In6.Cu" signal "IN3")
		(16 "In7.Cu" signal "GND3")
		(18 "In8.Cu" signal "VCC")
		(20 "In9.Cu" signal "VCC1")
		(22 "In10.Cu" signal "GND4")
		(24 "In11.Cu" signal "IN4")
		(26 "In12.Cu" signal "GND5")
		(28 "In13.Cu" signal "IN5")
		(30 "In14.Cu" signal "GND6")
		(32 "In15.Cu" signal "IN6")
		(34 "In16.Cu" signal "GND7")
		(2 "B.Cu" signal "BOTTOM")
		(9 "F.Adhes" user "F.Adhesive")
		(11 "B.Adhes" user "B.Adhesive")
		(13 "F.Paste" user "Package Geometry/Pastemask Top")
		(15 "B.Paste" user "Package Geometry/Pastemask Bottom")
		(5 "F.SilkS" user "Ref Des/Silkscreen Top")
		(7 "B.SilkS" user "Ref Des/Silkscreen Bottom")
		(1 "F.Mask" user "Board Geometry/Soldermask Top")
		(3 "B.Mask" user "Board Geometry/Soldermask Bottom")
		(17 "Dwgs.User" user "User.Drawings")
		(19 "Cmts.User" user "User.Comments")
		(21 "Eco1.User" user "User.Eco1")
		(23 "Eco2.User" user "User.Eco2")
		(25 "Edge.Cuts" user "Board Geometry/Outline")
		(27 "Margin" user)
		(31 "F.CrtYd" user "Package Geometry/Place Bound Top")
		(29 "B.CrtYd" user "Package Geometry/Place Bound Bottom")
		(35 "F.Fab" user "Ref Des/Assembly Top")
		(33 "B.Fab" user "Ref Des/Assembly Bottom")
	)
	(footprint ""
		(layer "F.Cu")
		(at 359.867962 -258.880102 180)
		(property "Reference" "U25"
			(at -45.78477 -62.086744 0)
			(unlocked yes)
			(layer "F.SilkS")
			(effects
				(font
					(size 0.7874 0.5842)
					(thickness 0.1524)
				)
			)
		)
		(property "Value" ""
			(at 0 0 180)
			(layer "F.Fab")
			(effects
				(font
					(size 1.27 1.27)
				)
			)
		)
		(duplicate_pad_numbers_are_jumpers no)
		(pad "N32" smd circle
			(at -5.020056 -27.090116 180)
			(size 0.450088 0.450088)
			(layers "F.Cu" "F.Mask" "F.Paste")
			(net "P5E_CPU0_G3_TX_DP<11>")
		)
		(pad "N33" smd circle
			(at -4.080002 -27.090116 180)
			(size 0.450088 0.450088)
			(layers "F.Cu" "F.Mask" "F.Paste")
			(net "P5E_CPU0_G3_TX_DN<11>")
		)
		(pad "N34" smd circle
			(at -3.139948 -27.090116 180)
			(size 0.450088 0.450088)
			(layers "F.Cu" "F.Mask" "F.Paste")
			(net "GND")
		)
		(pad "N35" smd circle
			(at -2.199894 -27.090116 180)
			(size 0.450088 0.450088)
			(layers "F.Cu" "F.Mask" "F.Paste")
			(net "PVDDCR_CPU0_P0")
		)
		(pad "N36" smd circle
			(at -1.260094 -27.090116 180)
			(size 0.450088 0.450088)
			(layers "F.Cu" "F.Mask" "F.Paste")
			(net "PVDDCR_CPU0_P0")
		)
		(pad "N40" smd circle
			(at 1.560068 -27.090116 180)
			(size 0.450088 0.450088)
			(layers "F.Cu" "F.Mask" "F.Paste")
			(net "PVDDCR_CPU0_P0")
		)
		(pad "N41" smd circle
			(at 2.500122 -27.090116 180)
			(size 0.450088 0.450088)
			(layers "F.Cu" "F.Mask" "F.Paste")
			(net "PVDDCR_CPU0_P0")
		)
		(pad "N42" smd circle
			(at 3.439922 -27.090116 180)
			(size 0.450088 0.450088)
			(layers "F.Cu" "F.Mask" "F.Paste")
			(net "GND")
		)
		(pad "N43" smd circle
			(at 4.379976 -27.090116 180)
			(size 0.450088 0.450088)
			(layers "F.Cu" "F.Mask" "F.Paste")
			(net "GMI_CPU1_G3_CPU0_G1_TX_DN<4>")
		)
		(pad "N44" smd circle
			(at 5.32003 -27.090116 180)
			(size 0.450088 0.450088)
			(layers "F.Cu" "F.Mask" "F.Paste")
			(net "GMI_CPU1_G3_CPU0_G1_TX_DP<4>")
		)
		(pad "N45" smd circle
			(at 6.260084 -27.090116 180)
			(size 0.450088 0.450088)
			(layers "F.Cu" "F.Mask" "F.Paste")
			(net "GND")
		)
		(pad "N46" smd circle
			(at 7.199884 -27.090116 180)
			(size 0.450088 0.450088)
			(layers "F.Cu" "F.Mask" "F.Paste")
			(net "GMI_CPU1_G3_CPU0_G1_TX_DN<7>")
		)
		(pad "N47" smd circle
			(at 8.139938 -27.090116 180)
			(size 0.450088 0.450088)
			(layers "F.Cu" "F.Mask" "F.Paste")
			(net "GMI_CPU1_G3_CPU0_G1_TX_DP<7>")
		)
		(pad "N48" smd circle
			(at 9.079992 -27.090116 180)
			(size 0.450088 0.450088)
			(layers "F.Cu" "F.Mask" "F.Paste")
			(net "GND")
		)
		(pad "N49" smd circle
			(at 10.020046 -27.090116 180)
			(size 0.450088 0.450088)
			(layers "F.Cu" "F.Mask" "F.Paste")
			(net "GMI_CPU1_G3_CPU0_G1_TX_DN<10>")
		)
		(pad "N50" smd circle
			(at 10.9601 -27.090116 180)
			(size 0.450088 0.450088)
			(layers "F.Cu" "F.Mask" "F.Paste")
			(net "GMI_CPU1_G3_CPU0_G1_TX_DP<10>")
		)
		(pad "N51" smd circle
			(at 11.8999 -27.090116 180)
			(size 0.450088 0.450088)
			(layers "F.Cu" "F.Mask" "F.Paste")
			(net "GND")
		)
		(pad "N52" smd circle
			(at 12.839954 -27.090116 180)
			(size 0.450088 0.450088)
			(layers "F.Cu" "F.Mask" "F.Paste")
			(net "GMI_CPU1_G2_CPU0_G0_TX_DN<15>")
		)
		(pad "N53" smd circle
			(at 13.780008 -27.090116 180)
			(size 0.450088 0.450088)
			(layers "F.Cu" "F.Mask" "F.Paste")
			(net "GMI_CPU1_G2_CPU0_G0_TX_DP<15>")
		)
		(pad "N54" smd circle
			(at 14.720062 -27.090116 180)
			(size 0.450088 0.450088)
			(layers "F.Cu" "F.Mask" "F.Paste")
			(net "GND")
		)
		(pad "N55" smd circle
			(at 15.660116 -27.090116 180)
			(size 0.450088 0.450088)
			(layers "F.Cu" "F.Mask" "F.Paste")
			(net "M_C_CPU0_SA_DQ<11>")
		)
		(pad "N56" smd circle
			(at 16.599916 -27.090116 180)
			(size 0.450088 0.450088)
			(layers "F.Cu" "F.Mask" "F.Paste")
			(net "GND")
		)
		(pad "N57" smd circle
			(at 17.53997 -27.090116 180)
			(size 0.450088 0.450088)
			(layers "F.Cu" "F.Mask" "F.Paste")
			(net "M_C_CPU0_SA_DQS_DP<1>")
		)
		(pad "N58" smd circle
			(at 18.480024 -27.090116 180)
			(size 0.450088 0.450088)
			(layers "F.Cu" "F.Mask" "F.Paste")
			(net "GND")
		)
		(pad "N59" smd circle
			(at 19.420078 -27.090116 180)
			(size 0.450088 0.450088)
			(layers "F.Cu" "F.Mask" "F.Paste")
			(net "M_D_CPU0_SA_DQ<11>")
		)
		(pad "N60" smd circle
			(at 20.359878 -27.090116 180)
			(size 0.450088 0.450088)
			(layers "F.Cu" "F.Mask" "F.Paste")
			(net "M_D_CPU0_SA_DQS_DP<1>")
		)
		(pad "N61" smd circle
			(at 21.299932 -27.090116 180)
			(size 0.450088 0.450088)
			(layers "F.Cu" "F.Mask" "F.Paste")
			(net "GND")
		)
		(pad "N62" smd circle
			(at 22.239986 -27.090116 180)
			(size 0.450088 0.450088)
			(layers "F.Cu" "F.Mask" "F.Paste")
			(net "M_B_CPU0_SA_DQ<11>")
		)
		(pad "N63" smd circle
			(at 23.18004 -27.090116 180)
			(size 0.450088 0.450088)
			(layers "F.Cu" "F.Mask" "F.Paste")
			(net "GND")
		)
		(pad "N64" smd circle
			(at 24.120094 -27.090116 180)
			(size 0.450088 0.450088)
			(layers "F.Cu" "F.Mask" "F.Paste")
			(net "M_B_CPU0_SA_DQS_DP<1>")
		)
		(pad "N65" smd circle
			(at 25.059894 -27.090116 180)
			(size 0.450088 0.450088)
			(layers "F.Cu" "F.Mask" "F.Paste")
			(net "GND")
		)
		(pad "N66" smd circle
			(at 25.999948 -27.090116 180)
			(size 0.450088 0.450088)
			(layers "F.Cu" "F.Mask" "F.Paste")
			(net "M_F_CPU0_SA_DQ<11>")
		)
		(pad "N67" smd circle
			(at 26.940002 -27.090116 180)
			(size 0.450088 0.450088)
			(layers "F.Cu" "F.Mask" "F.Paste")
			(net "M_F_CPU0_SA_DQS_DP<1>")
		)
		(pad "N68" smd circle
			(at 27.880056 -27.090116 180)
			(size 0.450088 0.450088)
			(layers "F.Cu" "F.Mask" "F.Paste")
			(net "GND")
		)
		(pad "N69" smd circle
			(at 28.82011 -27.090116 180)
			(size 0.450088 0.450088)
			(layers "F.Cu" "F.Mask" "F.Paste")
			(net "M_E_CPU0_SA_DQ<11>")
		)
		(pad "N70" smd circle
			(at 29.75991 -27.090116 180)
			(size 0.450088 0.450088)
			(layers "F.Cu" "F.Mask" "F.Paste")
			(net "GND")
		)
		(pad "N71" smd circle
			(at 30.699964 -27.090116 180)
			(size 0.450088 0.450088)
			(layers "F.Cu" "F.Mask" "F.Paste")
			(net "M_E_CPU0_SA_DQS_DP<1>")
		)
		(pad "N72" smd circle
			(at 31.640018 -27.090116 180)
			(size 0.450088 0.450088)
			(layers "F.Cu" "F.Mask" "F.Paste")
			(net "GND")
		)
		(pad "N73" smd circle
			(at 32.580072 -27.090116 180)
			(size 0.450088 0.450088)
			(layers "F.Cu" "F.Mask" "F.Paste")
			(net "M_A_CPU0_SA_DQ<11>")
		)
		(pad "N74" smd circle
			(at 33.519872 -27.090116 180)
			(size 0.450088 0.450088)
			(layers "F.Cu" "F.Mask" "F.Paste")
			(net "M_A_CPU0_SA_DQS_DP<1>")
		)
		(pad "N75" smd circle
			(at 34.459926 -27.090116 180)
			(size 0.450088 0.450088)
			(layers "F.Cu" "F.Mask" "F.Paste")
			(net "GND")
		)
		(pad "P2" smd circle
			(at -33.690052 -26.28011 180)
			(size 0.450088 0.450088)
			(layers "F.Cu" "F.Mask" "F.Paste")
			(net "M_G_CPU0_SA_DQS_DN<1>")
		)
		(pad "P3" smd circle
			(at -32.749998 -26.28011 180)
			(size 0.450088 0.450088)
			(layers "F.Cu" "F.Mask" "F.Paste")
			(net "GND")
		)
		(pad "P4" smd circle
			(at -31.809944 -26.28011 180)
			(size 0.450088 0.450088)
			(layers "F.Cu" "F.Mask" "F.Paste")
			(net "M_G_CPU0_SA_DQS_DN<6>")
		)
		(pad "P5" smd circle
			(at -30.86989 -26.28011 180)
			(size 0.450088 0.450088)
			(layers "F.Cu" "F.Mask" "F.Paste")
			(net "PVDDCR_SOC_P0")
		)
		(pad "P6" smd circle
			(at -29.93009 -26.28011 180)
			(size 0.450088 0.450088)
			(layers "F.Cu" "F.Mask" "F.Paste")
			(net "M_K_CPU0_SA_DQS_DN<1>")
		)
		(pad "P7" smd circle
			(at -28.990036 -26.28011 180)
			(size 0.450088 0.450088)
			(layers "F.Cu" "F.Mask" "F.Paste")
			(net "M_K_CPU0_SA_DQS_DN<6>")
		)
		(pad "P8" smd circle
			(at -28.049982 -26.28011 180)
			(size 0.450088 0.450088)
			(layers "F.Cu" "F.Mask" "F.Paste")
			(net "GND")
		)
		(pad "P9" smd circle
			(at -27.109928 -26.28011 180)
			(size 0.450088 0.450088)
			(layers "F.Cu" "F.Mask" "F.Paste")
			(net "M_L_CPU0_SA_DQS_DN<1>")
		)
		(pad "P10" smd circle
			(at -26.170128 -26.28011 180)
			(size 0.450088 0.450088)
			(layers "F.Cu" "F.Mask" "F.Paste")
			(net "GND")
		)
		(pad "P11" smd circle
			(at -25.230074 -26.28011 180)
			(size 0.450088 0.450088)
			(layers "F.Cu" "F.Mask" "F.Paste")
			(net "M_L_CPU0_SA_DQS_DN<6>")
		)
		(pad "P12" smd circle
			(at -24.29002 -26.28011 180)
			(size 0.450088 0.450088)
			(layers "F.Cu" "F.Mask" "F.Paste")
			(net "PVDDCR_SOC_P0")
		)
		(pad "P13" smd circle
			(at -23.349966 -26.28011 180)
			(size 0.450088 0.450088)
			(layers "F.Cu" "F.Mask" "F.Paste")
			(net "M_H_CPU0_SA_DQS_DN<1>")
		)
		(pad "P14" smd circle
			(at -22.409912 -26.28011 180)
			(size 0.450088 0.450088)
			(layers "F.Cu" "F.Mask" "F.Paste")
			(net "M_H_CPU0_SA_DQS_DN<6>")
		)
		(pad "P15" smd circle
			(at -21.470112 -26.28011 180)
			(size 0.450088 0.450088)
			(layers "F.Cu" "F.Mask" "F.Paste")
			(net "GND")
		)
		(pad "P16" smd circle
			(at -20.530058 -26.28011 180)
			(size 0.450088 0.450088)
			(layers "F.Cu" "F.Mask" "F.Paste")
			(net "M_J_CPU0_SA_DQS_DN<1>")
		)
		(pad "P17" smd circle
			(at -19.590004 -26.28011 180)
			(size 0.450088 0.450088)
			(layers "F.Cu" "F.Mask" "F.Paste")
			(net "GND")
		)
		(pad "P18" smd circle
			(at -18.64995 -26.28011 180)
			(size 0.450088 0.450088)
			(layers "F.Cu" "F.Mask" "F.Paste")
			(net "M_J_CPU0_SA_DQS_DN<6>")
		)
		(pad "P19" smd circle
			(at -17.709896 -26.28011 180)
			(size 0.450088 0.450088)
			(layers "F.Cu" "F.Mask" "F.Paste")
			(net "PVDDCR_SOC_P0")
		)
		(pad "P20" smd circle
			(at -16.770096 -26.28011 180)
			(size 0.450088 0.450088)
			(layers "F.Cu" "F.Mask" "F.Paste")
			(net "M_I_CPU0_SA_DQS_DN<1>")
		)
		(pad "P21" smd circle
			(at -15.830042 -26.28011 180)
			(size 0.450088 0.450088)
			(layers "F.Cu" "F.Mask" "F.Paste")
			(net "M_I_CPU0_SA_DQS_DN<6>")
		)
		(pad "P22" smd circle
			(at -14.889988 -26.28011 180)
			(size 0.450088 0.450088)
			(layers "F.Cu" "F.Mask" "F.Paste")
			(net "PVDDCR_SOC_P0")
		)
		(pad "P23" smd circle
			(at -13.949934 -26.28011 180)
			(size 0.450088 0.450088)
			(layers "F.Cu" "F.Mask" "F.Paste")
			(net "GND")
		)
		(pad "P24" smd circle
			(at -13.00988 -26.28011 180)
			(size 0.450088 0.450088)
			(layers "F.Cu" "F.Mask" "F.Paste")
			(net "GND")
		)
		(pad "P25" smd circle
			(at -12.07008 -26.28011 180)
			(size 0.450088 0.450088)
			(layers "F.Cu" "F.Mask" "F.Paste")
			(net "GND")
		)
		(pad "P26" smd circle
			(at -11.130026 -26.28011 180)
			(size 0.450088 0.450088)
			(layers "F.Cu" "F.Mask" "F.Paste")
			(net "GND")
		)
		(pad "P27" smd circle
			(at -10.189972 -26.28011 180)
			(size 0.450088 0.450088)
			(layers "F.Cu" "F.Mask" "F.Paste")
			(net "GND")
		)
		(pad "P28" smd circle
			(at -9.249918 -26.28011 180)
			(size 0.450088 0.450088)
			(layers "F.Cu" "F.Mask" "F.Paste")
			(net "GND")
		)
		(pad "P29" smd circle
			(at -8.310118 -26.28011 180)
			(size 0.450088 0.450088)
			(layers "F.Cu" "F.Mask" "F.Paste")
			(net "GND")
		)
		(pad "P30" smd circle
			(at -7.370064 -26.28011 180)
			(size 0.450088 0.450088)
			(layers "F.Cu" "F.Mask" "F.Paste")
			(net "GND")
		)
		(pad "P31" smd circle
			(at -6.43001 -26.28011 180)
			(size 0.450088 0.450088)
			(layers "F.Cu" "F.Mask" "F.Paste")
			(net "GND")
		)
		(pad "P32" smd circle
			(at -5.489956 -26.28011 180)
			(size 0.450088 0.450088)
			(layers "F.Cu" "F.Mask" "F.Paste")
			(net "GND")
		)
		(pad "P33" smd circle
			(at -4.549902 -26.28011 180)
			(size 0.450088 0.450088)
			(layers "F.Cu" "F.Mask" "F.Paste")
			(net "GND")
		)
		(pad "P34" smd circle
			(at -3.610102 -26.28011 180)
			(size 0.450088 0.450088)
			(layers "F.Cu" "F.Mask" "F.Paste")
			(net "GND")
		)
		(pad "P35" smd circle
			(at -2.670048 -26.28011 180)
			(size 0.450088 0.450088)
			(layers "F.Cu" "F.Mask" "F.Paste")
			(net "P5E_CPU0_G3_TX_DP<13>")
		)
		(pad "P36" smd circle
			(at -1.729994 -26.28011 180)
			(size 0.450088 0.450088)
			(layers "F.Cu" "F.Mask" "F.Paste")
			(net "P5E_CPU0_G3_TX_DN<13>")
		)
		(pad "P37" smd circle
			(at -0.78994 -26.28011 180)
			(size 0.450088 0.450088)
			(layers "F.Cu" "F.Mask" "F.Paste")
			(net "GND")
		)
		(pad "P39" smd circle
			(at 1.089914 -26.28011 180)
			(size 0.450088 0.450088)
			(layers "F.Cu" "F.Mask" "F.Paste")
			(net "GND")
		)
		(pad "P40" smd circle
			(at 2.029968 -26.28011 180)
			(size 0.450088 0.450088)
			(layers "F.Cu" "F.Mask" "F.Paste")
			(net "GMI_CPU1_G3_CPU0_G1_TX_DN<2>")
		)
		(pad "P41" smd circle
			(at 2.970022 -26.28011 180)
			(size 0.450088 0.450088)
			(layers "F.Cu" "F.Mask" "F.Paste")
			(net "GMI_CPU1_G3_CPU0_G1_TX_DP<2>")
		)
		(pad "P42" smd circle
			(at 3.910076 -26.28011 180)
			(size 0.450088 0.450088)
			(layers "F.Cu" "F.Mask" "F.Paste")
			(net "GND")
		)
		(pad "P43" smd circle
			(at 4.849876 -26.28011 180)
			(size 0.450088 0.450088)
			(layers "F.Cu" "F.Mask" "F.Paste")
			(net "GND")
		)
		(pad "P44" smd circle
			(at 5.78993 -26.28011 180)
			(size 0.450088 0.450088)
			(layers "F.Cu" "F.Mask" "F.Paste")
			(net "GND")
		)
		(pad "P45" smd circle
			(at 6.729984 -26.28011 180)
			(size 0.450088 0.450088)
			(layers "F.Cu" "F.Mask" "F.Paste")
			(net "GND")
		)
		(pad "P46" smd circle
			(at 7.670038 -26.28011 180)
			(size 0.450088 0.450088)
			(layers "F.Cu" "F.Mask" "F.Paste")
			(net "GND")
		)
		(pad "P47" smd circle
			(at 8.610092 -26.28011 180)
			(size 0.450088 0.450088)
			(layers "F.Cu" "F.Mask" "F.Paste")
			(net "GND")
		)
		(pad "P48" smd circle
			(at 9.549892 -26.28011 180)
			(size 0.450088 0.450088)
			(layers "F.Cu" "F.Mask" "F.Paste")
			(net "GND")
		)
		(pad "P49" smd circle
			(at 10.489946 -26.28011 180)
			(size 0.450088 0.450088)
			(layers "F.Cu" "F.Mask" "F.Paste")
			(net "GND")
		)
		(pad "P50" smd circle
			(at 11.43 -26.28011 180)
			(size 0.450088 0.450088)
			(layers "F.Cu" "F.Mask" "F.Paste")
			(net "GND")
		)
		(pad "P51" smd circle
			(at 12.370054 -26.28011 180)
			(size 0.450088 0.450088)
			(layers "F.Cu" "F.Mask" "F.Paste")
			(net "GND")
		)
		(pad "P52" smd circle
			(at 13.310108 -26.28011 180)
			(size 0.450088 0.450088)
			(layers "F.Cu" "F.Mask" "F.Paste")
			(net "GND")
		)
		(pad "P53" smd circle
			(at 14.249908 -26.28011 180)
			(size 0.450088 0.450088)
			(layers "F.Cu" "F.Mask" "F.Paste")
			(net "GND")
		)
		(pad "P54" smd circle
			(at 15.189962 -26.28011 180)
			(size 0.450088 0.450088)
			(layers "F.Cu" "F.Mask" "F.Paste")
			(net "PVDDIO_P0")
		)
		(pad "P55" smd circle
			(at 16.130016 -26.28011 180)
			(size 0.450088 0.450088)
			(layers "F.Cu" "F.Mask" "F.Paste")
			(net "M_C_CPU0_SA_DQS_DN<6>")
		)
		(pad "P56" smd circle
			(at 17.07007 -26.28011 180)
			(size 0.450088 0.450088)
			(layers "F.Cu" "F.Mask" "F.Paste")
			(net "M_C_CPU0_SA_DQS_DN<1>")
		)
		(pad "P57" smd circle
			(at 18.010124 -26.28011 180)
			(size 0.450088 0.450088)
			(layers "F.Cu" "F.Mask" "F.Paste")
			(net "PVDDIO_P0")
		)
		(pad "P58" smd circle
			(at 18.949924 -26.28011 180)
			(size 0.450088 0.450088)
			(layers "F.Cu" "F.Mask" "F.Paste")
			(net "M_D_CPU0_SA_DQS_DN<6>")
		)
		(pad "P59" smd circle
			(at 19.889978 -26.28011 180)
			(size 0.450088 0.450088)
			(layers "F.Cu" "F.Mask" "F.Paste")
			(net "GND")
		)
		(pad "P60" smd circle
			(at 20.830032 -26.28011 180)
			(size 0.450088 0.450088)
			(layers "F.Cu" "F.Mask" "F.Paste")
			(net "M_D_CPU0_SA_DQS_DN<1>")
		)
		(pad "P61" smd circle
			(at 21.770086 -26.28011 180)
			(size 0.450088 0.450088)
			(layers "F.Cu" "F.Mask" "F.Paste")
			(net "GND")
		)
		(pad "P62" smd circle
			(at 22.709886 -26.28011 180)
			(size 0.450088 0.450088)
			(layers "F.Cu" "F.Mask" "F.Paste")
			(net "M_B_CPU0_SA_DQS_DN<6>")
		)
		(pad "P63" smd circle
			(at 23.64994 -26.28011 180)
			(size 0.450088 0.450088)
			(layers "F.Cu" "F.Mask" "F.Paste")
			(net "M_B_CPU0_SA_DQS_DN<1>")
		)
		(pad "P64" smd circle
			(at 24.589994 -26.28011 180)
			(size 0.450088 0.450088)
			(layers "F.Cu" "F.Mask" "F.Paste")
			(net "PVDDIO_P0")
		)
		(pad "P65" smd circle
			(at 25.530048 -26.28011 180)
			(size 0.450088 0.450088)
			(layers "F.Cu" "F.Mask" "F.Paste")
			(net "M_F_CPU0_SA_DQS_DN<6>")
		)
		(pad "P66" smd circle
			(at 26.470102 -26.28011 180)
			(size 0.450088 0.450088)
			(layers "F.Cu" "F.Mask" "F.Paste")
			(net "GND")
		)
		(pad "P67" smd circle
			(at 27.409902 -26.28011 180)
			(size 0.450088 0.450088)
			(layers "F.Cu" "F.Mask" "F.Paste")
			(net "M_F_CPU0_SA_DQS_DN<1>")
		)
		(pad "P68" smd circle
			(at 28.349956 -26.28011 180)
			(size 0.450088 0.450088)
			(layers "F.Cu" "F.Mask" "F.Paste")
			(net "GND")
		)
		(pad "P69" smd circle
			(at 29.29001 -26.28011 180)
			(size 0.450088 0.450088)
			(layers "F.Cu" "F.Mask" "F.Paste")
			(net "M_E_CPU0_SA_DQS_DN<6>")
		)
		(pad "P70" smd circle
			(at 30.230064 -26.28011 180)
			(size 0.450088 0.450088)
			(layers "F.Cu" "F.Mask" "F.Paste")
			(net "M_E_CPU0_SA_DQS_DN<1>")
		)
		(pad "P71" smd circle
			(at 31.170118 -26.28011 180)
			(size 0.450088 0.450088)
			(layers "F.Cu" "F.Mask" "F.Paste")
			(net "PVDDIO_P0")
		)
	)
)
